# T6G (Grand Teton) — schematic netlist excerpt (pin names and nets, part order shuffled) for the footprints in the layout excerpt that follows; sources: Cadence DE-HDL packaged netlist, KiCad conversion of 04192023_DAF0TMB3IC0_F0TG_MB_C_brd_V02_OCP.brd

C6634  Q_CAP_DIFFBUS  DIFF BUS_0.22UF 6.3V 20% X6S  pkg C0201  page 319 : \1\ = P5E_CPU1_P0_TX_BUF_C_DN<2> ; \2\ = P5E_CPU1_P0_TX_BUF_DN<2>
R3870  Q_RES  0 5% CHIP  pkg 0402LF  page 134 : A = P12V_OCP_SENSE_1 ; B = P12V_OCP_SFF_ISENSE_MAM_TIC
R1330  Q_RES  0 5% EMPTY  pkg 0402LF  page 159 : A = I3C_SPD_DDRAF_CPU0_BYPASS_SCL ; B = I3C_SPD_DDRAF_CPU0_SCL

(kicad_pcb
	(version 20260206)
	(generator "pcbnew")
	(generator_version "10.0")
	(general
		(thickness 1.6)
		(legacy_teardrops no)
	)
	(paper "A4")
	(title_block
		(title "04192023_DAF0TMB3IC0_F0TG_MB_C_brd_V02_OCP.brd")
		(comment 1 "Grand Teton / footprints 464-466 of 8354")
	)
	(layers
		(0 "F.Cu" signal "TOP")
		(4 "In1.Cu" signal "GND")
		(6 "In2.Cu" signal "IN1")
		(8 "In3.Cu" signal "GND1")
		(10 "In4.Cu" signal "IN2")
		(12 "In5.Cu" signal "GND2")
		(14 "In6.Cu" signal "IN3")
		(16 "In7.Cu" signal "GND3")
		(18 "In8.Cu" signal "VCC")
		(20 "In9.Cu" signal "VCC1")
		(22 "In10.Cu" signal "GND4")
		(24 "In11.Cu" signal "IN4")
		(26 "In12.Cu" signal "GND5")
		(28 "In13.Cu" signal "IN5")
		(30 "In14.Cu" signal "GND6")
		(32 "In15.Cu" signal "IN6")
		(34 "In16.Cu" signal "GND7")
		(2 "B.Cu" signal "BOTTOM")
		(9 "F.Adhes" user "F.Adhesive")
		(11 "B.Adhes" user "B.Adhesive")
		(13 "F.Paste" user "Package Geometry/Pastemask Top")
		(15 "B.Paste" user "Package Geometry/Pastemask Bottom")
		(5 "F.SilkS" user "Ref Des/Silkscreen Top")
		(7 "B.SilkS" user "Ref Des/Silkscreen Bottom")
		(1 "F.Mask" user "Board Geometry/Soldermask Top")
		(3 "B.Mask" user "Board Geometry/Soldermask Bottom")
		(17 "Dwgs.User" user "User.Drawings")
		(19 "Cmts.User" user "User.Comments")
		(21 "Eco1.User" user "User.Eco1")
		(23 "Eco2.User" user "User.Eco2")
		(25 "Edge.Cuts" user "Board Geometry/Outline")
		(27 "Margin" user)
		(31 "F.CrtYd" user "Package Geometry/Place Bound Top")
		(29 "B.CrtYd" user "Package Geometry/Place Bound Bottom")
		(35 "F.Fab" user "Ref Des/Assembly Top")
		(33 "B.Fab" user "Ref Des/Assembly Bottom")
	)
	(footprint ""
		(layer "F.Cu")
		(at 297.315128 -146.202908 180)
		(property "Reference" "R1330"
			(at 0 0 180)
			(layer "F.SilkS")
			(hide yes)
			(effects
				(font
					(size 1.27 1.27)
				)
			)
		)
		(property "Value" ""
			(at 0 0 180)
			(layer "F.Fab")
			(effects
				(font
					(size 1.27 1.27)
				)
			)
		)
		(duplicate_pad_numbers_are_jumpers no)
		(fp_line
			(start 0.7874 0.4064)
			(end -0.7874 0.4064)
			(stroke
				(width 0.1524)
				(type default)
			)
			(layer "F.SilkS")
		)
		(fp_line
			(start 0.7874 -0.4064)
			(end 0.7874 0.4064)
			(stroke
				(width 0.1524)
				(type default)
			)
			(layer "F.SilkS")
		)
		(fp_line
			(start -0.7874 0.4064)
			(end -0.7874 -0.4064)
			(stroke
				(width 0.1524)
				(type default)
			)
			(layer "F.SilkS")
		)
		(fp_line
			(start -0.7874 -0.4064)
			(end 0.7874 -0.4064)
			(stroke
				(width 0.1524)
				(type default)
			)
			(layer "F.SilkS")
		)
		(fp_line
			(start 0.67945 0.3048)
			(end 0.120396 0.3048)
			(stroke
				(width 0.1)
				(type default)
			)
			(layer "F.Fab")
		)
		(fp_line
			(start 0.67945 -0.3048)
			(end 0.67945 0.3048)
			(stroke
				(width 0.1)
				(type default)
			)
			(layer "F.Fab")
		)
		(fp_line
			(start 0.12065 -0.2794)
			(end 0.12065 -0.3048)
			(stroke
				(width 0.1)
				(type default)
			)
			(layer "F.Fab")
		)
		(fp_line
			(start 0.12065 -0.3048)
			(end 0.67945 -0.3048)
			(stroke
				(width 0.1)
				(type default)
			)
			(layer "F.Fab")
		)
		(fp_line
			(start 0.120396 0.3048)
			(end 0.120396 0.2794)
			(stroke
				(width 0.1)
				(type default)
			)
			(layer "F.Fab")
		)
		(fp_line
			(start 0.120396 0.2794)
			(end -0.12065 0.2794)
			(stroke
				(width 0.1)
				(type default)
			)
			(layer "F.Fab")
		)
		(fp_line
			(start -0.12065 0.3048)
			(end -0.67945 0.3048)
			(stroke
				(width 0.1)
				(type default)
			)
			(layer "F.Fab")
		)
		(fp_line
			(start -0.12065 0.2794)
			(end -0.12065 0.3048)
			(stroke
				(width 0.1)
				(type default)
			)
			(layer "F.Fab")
		)
		(fp_line
			(start -0.12065 -0.2794)
			(end 0.12065 -0.2794)
			(stroke
				(width 0.1)
				(type default)
			)
			(layer "F.Fab")
		)
		(fp_line
			(start -0.12065 -0.305054)
			(end -0.12065 -0.2794)
			(stroke
				(width 0.1)
				(type default)
			)
			(layer "F.Fab")
		)
		(fp_line
			(start -0.67945 0.3048)
			(end -0.67945 -0.305054)
			(stroke
				(width 0.1)
				(type default)
			)
			(layer "F.Fab")
		)
		(fp_line
			(start -0.67945 -0.305054)
			(end -0.12065 -0.305054)
			(stroke
				(width 0.1)
				(type default)
			)
			(layer "F.Fab")
		)
		(pad "1" smd rect
			(at -0.40005 0)
			(size 0.4572 0.508)
			(layers "F.Cu" "F.Mask" "F.Paste")
			(net "I3C_SPD_DDRAF_CPU0_BYPASS_SCL")
		)
		(pad "2" smd rect
			(at 0.40005 0)
			(size 0.4572 0.508)
			(layers "F.Cu" "F.Mask" "F.Paste")
			(net "I3C_SPD_DDRAF_CPU0_SCL")
		)
	)
	(footprint ""
		(layer "F.Cu")
		(at 435.181248 -35.489388 90)
		(property "Reference" "R3870"
			(at 0 0 90)
			(layer "F.SilkS")
			(hide yes)
			(effects
				(font
					(size 1.27 1.27)
				)
			)
		)
		(property "Value" ""
			(at 0 0 90)
			(layer "F.Fab")
			(effects
				(font
					(size 1.27 1.27)
				)
			)
		)
		(duplicate_pad_numbers_are_jumpers no)
		(fp_line
			(start 0.7874 -0.4064)
			(end 0.7874 0.4064)
			(stroke
				(width 0.1524)
				(type default)
			)
			(layer "F.SilkS")
		)
		(fp_line
			(start -0.7874 -0.4064)
			(end 0.7874 -0.4064)
			(stroke
				(width 0.1524)
				(type default)
			)
			(layer "F.SilkS")
		)
		(fp_line
			(start 0.7874 0.4064)
			(end -0.7874 0.4064)
			(stroke
				(width 0.1524)
				(type default)
			)
			(layer "F.SilkS")
		)
		(fp_line
			(start -0.7874 0.4064)
			(end -0.7874 -0.4064)
			(stroke
				(width 0.1524)
				(type default)
			)
			(layer "F.SilkS")
		)
		(fp_line
			(start -0.12065 -0.305054)
			(end -0.12065 -0.2794)
			(stroke
				(width 0.1)
				(type default)
			)
			(layer "F.Fab")
		)
		(fp_line
			(start -0.67945 -0.305054)
			(end -0.12065 -0.305054)
			(stroke
				(width 0.1)
				(type default)
			)
			(layer "F.Fab")
		)
		(fp_line
			(start 0.67945 -0.3048)
			(end 0.67945 0.3048)
			(stroke
				(width 0.1)
				(type default)
			)
			(layer "F.Fab")
		)
		(fp_line
			(start 0.12065 -0.3048)
			(end 0.67945 -0.3048)
			(stroke
				(width 0.1)
				(type default)
			)
			(layer "F.Fab")
		)
		(fp_line
			(start 0.12065 -0.2794)
			(end 0.12065 -0.3048)
			(stroke
				(width 0.1)
				(type default)
			)
			(layer "F.Fab")
		)
		(fp_line
			(start -0.12065 -0.2794)
			(end 0.12065 -0.2794)
			(stroke
				(width 0.1)
				(type default)
			)
			(layer "F.Fab")
		)
		(fp_line
			(start 0.120396 0.2794)
			(end -0.12065 0.2794)
			(stroke
				(width 0.1)
				(type default)
			)
			(layer "F.Fab")
		)
		(fp_line
			(start -0.12065 0.2794)
			(end -0.12065 0.3048)
			(stroke
				(width 0.1)
				(type default)
			)
			(layer "F.Fab")
		)
		(fp_line
			(start 0.67945 0.3048)
			(end 0.120396 0.3048)
			(stroke
				(width 0.1)
				(type default)
			)
			(layer "F.Fab")
		)
		(fp_line
			(start 0.120396 0.3048)
			(end 0.120396 0.2794)
			(stroke
				(width 0.1)
				(type default)
			)
			(layer "F.Fab")
		)
		(fp_line
			(start -0.12065 0.3048)
			(end -0.67945 0.3048)
			(stroke
				(width 0.1)
				(type default)
			)
			(layer "F.Fab")
		)
		(fp_line
			(start -0.67945 0.3048)
			(end -0.67945 -0.305054)
			(stroke
				(width 0.1)
				(type default)
			)
			(layer "F.Fab")
		)
		(pad "1" smd circle
			(at -0.40005 0 90)
			(size 0 0)
			(layers "F.Cu" "F.Mask" "F.Paste")
			(net "P12V_OCP_SENSE_1")
		)
		(pad "2" smd circle
			(at 0.40005 0 90)
			(size 0 0)
			(layers "F.Cu" "F.Mask" "F.Paste")
			(net "P12V_OCP_SFF_ISENSE_MAM_TIC")
		)
	)
	(footprint ""
		(layer "F.Cu")
		(at 53.895244 -408.517344 -90)
		(property "Reference" "C6634"
			(at 0 0 270)
			(layer "F.SilkS")
			(hide yes)
			(effects
				(font
					(size 1.27 1.27)
				)
			)
		)
		(property "Value" ""
			(at 0 0 270)
			(layer "F.Fab")
			(effects
				(font
					(size 1.27 1.27)
				)
			)
		)
		(duplicate_pad_numbers_are_jumpers no)
		(fp_line
			(start -0.299974 0.150114)
			(end -0.299974 -0.150114)
			(stroke
				(width 0.1)
				(type default)
			)
			(layer "F.Fab")
		)
		(fp_line
			(start 0.299974 0.150114)
			(end -0.299974 0.150114)
			(stroke
				(width 0.1)
				(type default)
			)
			(layer "F.Fab")
		)
		(fp_line
			(start -0.299974 -0.150114)
			(end 0.299974 -0.150114)
			(stroke
				(width 0.1)
				(type default)
			)
			(layer "F.Fab")
		)
		(fp_line
			(start 0.299974 -0.150114)
			(end 0.299974 0.150114)
			(stroke
				(width 0.1)
				(type default)
			)
			(layer "F.Fab")
		)
		(pad "1" smd rect
			(at -0.2667 0 270)
			(size 0.3048 0.381)
			(layers "F.Cu" "F.Mask" "F.Paste")
			(net "P5E_CPU1_P0_TX_BUF_C_DN<2>")
		)
		(pad "2" smd rect
			(at 0.2667 0 270)
			(size 0.3048 0.381)
			(layers "F.Cu" "F.Mask" "F.Paste")
			(net "P5E_CPU1_P0_TX_BUF_DN<2>")
		)
	)
)
